(kicad_pcb
	(version 20260206)
	(generator "pcbnew")
	(generator_version "10.0")
	(general
		(thickness 1.6)
		(legacy_teardrops no)
	)
	(paper "A4")
	(title_block
		(title "Bryce Canyon_F.DPB_16315-1-OCP.brd")
		(comment 1 "Bryce Canyon / footprints 780-787 of 2223")
	)
	(layers
		(0 "F.Cu" signal "TOP")
		(4 "In1.Cu" signal "L2GND")
		(6 "In2.Cu" signal "L3")
		(8 "In3.Cu" signal "L4GND")
		(10 "In4.Cu" signal "L5")
		(12 "In5.Cu" signal "L6VCC")
		(14 "In6.Cu" signal "L7VCC")
		(16 "In7.Cu" signal "L8")
		(18 "In8.Cu" signal "L9GND")
		(20 "In9.Cu" signal "L10")
		(22 "In10.Cu" signal "L11GND")
		(2 "B.Cu" signal "BOTTOM")
		(9 "F.Adhes" user "F.Adhesive")
		(11 "B.Adhes" user "B.Adhesive")
		(13 "F.Paste" user "Package Geometry/Pastemask Top")
		(15 "B.Paste" user "Package Geometry/Pastemask Bottom")
		(5 "F.SilkS" user "Ref Des/Silkscreen Top")
		(7 "B.SilkS" user "Ref Des/Silkscreen Bottom")
		(1 "F.Mask" user "Board Geometry/Soldermask Top")
		(3 "B.Mask" user "Board Geometry/Soldermask Bottom")
		(17 "Dwgs.User" user "User.Drawings")
		(19 "Cmts.User" user "User.Comments")
		(21 "Eco1.User" user "User.Eco1")
		(23 "Eco2.User" user "User.Eco2")
		(25 "Edge.Cuts" user "Board Geometry/Outline")
		(27 "Margin" user)
		(31 "F.CrtYd" user "Package Geometry/Place Bound Top")
		(29 "B.CrtYd" user "Package Geometry/Place Bound Bottom")
		(35 "F.Fab" user "Ref Des/Assembly Top")
		(33 "B.Fab" user "Ref Des/Assembly Bottom")
	)
	(footprint ""
		(layer "F.Cu")
		(at 426.120052 -303.954942 180)
		(property "Reference" "C161"
			(at 0 0 180)
			(layer "F.SilkS")
			(hide yes)
			(effects
				(font
					(size 1.27 1.27)
				)
			)
		)
		(property "Value" "SC4D7U25V5KX-1-GP"
			(at -0.0762 -6.1214 180)
			(unlocked yes)
			(layer "F.Fab")
			(hide yes)
			(effects
				(font
					(size 1.016 1.016)
					(thickness 0.1524)
				)
			)
		)
		(property "Device Type" "C805H58"
			(at -0.0762 -8.1534 180)
			(unlocked yes)
			(layer "F.Fab")
			(hide yes)
			(effects
				(font
					(size 1.016 1.016)
					(thickness 0.1524)
				)
			)
		)
		(duplicate_pad_numbers_are_jumpers no)
		(fp_line
			(start 0.635 0)
			(end -0.635 0)
			(stroke
				(width 0.508)
				(type default)
			)
			(layer "F.SilkS")
		)
		(fp_rect
			(start -0.9652 1.778)
			(end 0.9652 -1.778)
			(stroke
				(width 0)
				(type default)
			)
			(fill no)
			(layer "F.CrtYd")
		)
		(fp_poly
			(pts
				(xy -0.9652 -1.778) (xy 0.9652 -1.778) (xy 0.9652 1.778) (xy -0.9652 1.778)
			)
			(stroke
				(width 0)
				(type default)
			)
			(fill no)
			(layer "F.Fab")
		)
		(pad "1" smd rect
			(at 0 -0.9652 180)
			(size 1.397 1.143)
			(layers "F.Cu" "F.Mask" "F.Paste")
			(net "P12V_HDD9")
		)
		(pad "2" smd rect
			(at 0 0.9652 180)
			(size 1.397 1.143)
			(layers "F.Cu" "F.Mask" "F.Paste")
			(net "GND")
		)
	)
	(footprint ""
		(layer "F.Cu")
		(at 248.466102 -394.580364 -90)
		(property "Reference" "R1167"
			(at 0 0 270)
			(layer "F.SilkS")
			(hide yes)
			(effects
				(font
					(size 1.27 1.27)
				)
			)
		)
		(property "Value" "49K9R2F-L-GP"
			(at 0.064008 -3.993896 270)
			(unlocked yes)
			(layer "F.Fab")
			(hide yes)
			(effects
				(font
					(size 1.016 1.016)
					(thickness 0.1524)
				)
			)
		)
		(property "Device Type" "R402H16"
			(at 0.064008 -5.517896 270)
			(unlocked yes)
			(layer "F.Fab")
			(hide yes)
			(effects
				(font
					(size 1.016 1.016)
					(thickness 0.1524)
				)
			)
		)
		(duplicate_pad_numbers_are_jumpers no)
		(fp_line
			(start -0.508 -0.9398)
			(end -0.508 0.9398)
			(stroke
				(width 0.1524)
				(type default)
			)
			(layer "F.SilkS")
		)
		(fp_line
			(start 0.508 -0.9398)
			(end -0.508 -0.9398)
			(stroke
				(width 0.1524)
				(type default)
			)
			(layer "F.SilkS")
		)
		(fp_rect
			(start -0.508 0.9398)
			(end 0.508 -0.9398)
			(stroke
				(width 0)
				(type default)
			)
			(fill no)
			(layer "F.CrtYd")
		)
		(fp_rect
			(start -0.508 0.9398)
			(end 0.508 -0.9398)
			(stroke
				(width 0)
				(type default)
			)
			(fill no)
			(layer "F.Fab")
		)
		(pad "1" smd custom
			(at 0 -0.4445 270)
			(size 0.1397 0.1397)
			(layers "F.Cu" "F.Mask" "F.Paste")
			(net "P12V_IN")
			(options
				(clearance outline)
				(anchor circle)
			)
			(primitives
				(gr_poly
					(pts
						(arc
							(start -0.1778 -0.2794)
							(mid -0.249642 -0.249642)
							(end -0.2794 -0.1778)
						)
						(arc
							(start -0.2794 0.1778)
							(mid -0.249642 0.249642)
							(end -0.1778 0.2794)
						)
						(arc
							(start 0.1778 0.2794)
							(mid 0.249642 0.249642)
							(end 0.2794 0.1778)
						)
						(arc
							(start 0.2794 -0.1778)
							(mid 0.249642 -0.249642)
							(end 0.1778 -0.2794)
						)
					)
					(width 0)
					(fill yes)
				)
			)
		)
		(pad "2" smd custom
			(at 0 0.4445 270)
			(size 0.1397 0.1397)
			(layers "F.Cu" "F.Mask" "F.Paste")
			(net "MB3_CM_OV_R")
			(options
				(clearance outline)
				(anchor circle)
			)
			(primitives
				(gr_poly
					(pts
						(arc
							(start -0.1778 -0.2794)
							(mid -0.249642 -0.249642)
							(end -0.2794 -0.1778)
						)
						(arc
							(start -0.2794 0.1778)
							(mid -0.249642 0.249642)
							(end -0.1778 0.2794)
						)
						(arc
							(start 0.1778 0.2794)
							(mid 0.249642 0.249642)
							(end 0.2794 0.1778)
						)
						(arc
							(start 0.2794 -0.1778)
							(mid 0.249642 -0.249642)
							(end 0.1778 -0.2794)
						)
					)
					(width 0)
					(fill yes)
				)
			)
		)
	)
	(footprint ""
		(layer "F.Cu")
		(at 48.961802 -143.46555)
		(property "Reference" "R1228"
			(at 0 0 0)
			(layer "F.SilkS")
			(hide yes)
			(effects
				(font
					(size 1.27 1.27)
				)
			)
		)
		(property "Value" "0R3J-0-U-GP"
			(at -0.0254 -2.5146 0)
			(unlocked yes)
			(layer "F.Fab")
			(hide yes)
			(effects
				(font
					(size 1.016 1.016)
					(thickness 0.1524)
				)
			)
		)
		(property "Device Type" "R603H22"
			(at -0.0254 -4.0386 0)
			(unlocked yes)
			(layer "F.Fab")
			(hide yes)
			(effects
				(font
					(size 1.016 1.016)
					(thickness 0.1524)
				)
			)
		)
		(duplicate_pad_numbers_are_jumpers no)
		(fp_line
			(start -0.4826 0)
			(end -0.2032 0)
			(stroke
				(width 0.2032)
				(type default)
			)
			(layer "F.SilkS")
		)
		(fp_line
			(start 0.2032 0)
			(end 0.4826 0)
			(stroke
				(width 0.2032)
				(type default)
			)
			(layer "F.SilkS")
		)
		(fp_rect
			(start -0.5842 1.3335)
			(end 0.5842 -1.3335)
			(stroke
				(width 0)
				(type default)
			)
			(fill no)
			(layer "F.CrtYd")
		)
		(fp_rect
			(start -0.5842 1.3335)
			(end 0.5842 -1.3335)
			(stroke
				(width 0)
				(type default)
			)
			(fill no)
			(layer "F.Fab")
		)
		(pad "1" smd custom
			(at 0 -0.762)
			(size 0.2159 0.2159)
			(layers "F.Cu" "F.Mask" "F.Paste")
			(net "P5V_B_VBST")
			(options
				(clearance outline)
				(anchor circle)
			)
			(primitives
				(gr_poly
					(pts
						(arc
							(start -0.3302 -0.4318)
							(mid -0.402042 -0.402042)
							(end -0.4318 -0.3302)
						)
						(arc
							(start -0.4318 0.3302)
							(mid -0.402042 0.402042)
							(end -0.3302 0.4318)
						)
						(arc
							(start 0.3302 0.4318)
							(mid 0.402042 0.402042)
							(end 0.4318 0.3302)
						)
						(arc
							(start 0.4318 -0.3302)
							(mid 0.402042 -0.402042)
							(end 0.3302 -0.4318)
						)
					)
					(width 0)
					(fill yes)
				)
			)
		)
		(pad "2" smd custom
			(at 0 0.762)
			(size 0.2159 0.2159)
			(layers "F.Cu" "F.Mask" "F.Paste")
			(net "P5V_B_VBST_RC")
			(options
				(clearance outline)
				(anchor circle)
			)
			(primitives
				(gr_poly
					(pts
						(arc
							(start -0.3302 -0.4318)
							(mid -0.402042 -0.402042)
							(end -0.4318 -0.3302)
						)
						(arc
							(start -0.4318 0.3302)
							(mid -0.402042 0.402042)
							(end -0.3302 0.4318)
						)
						(arc
							(start 0.3302 0.4318)
							(mid 0.402042 0.402042)
							(end 0.4318 0.3302)
						)
						(arc
							(start 0.4318 -0.3302)
							(mid 0.402042 -0.402042)
							(end 0.3302 -0.4318)
						)
					)
					(width 0)
					(fill yes)
				)
			)
		)
	)
	(footprint ""
		(layer "F.Cu")
		(at 276.242272 22.225 90)
		(property "Reference" "R633"
			(at 0 0 90)
			(layer "F.SilkS")
			(hide yes)
			(effects
				(font
					(size 1.27 1.27)
				)
			)
		)
		(property "Value" "10KR2F-2-GP"
			(at 0.064008 -3.993896 90)
			(unlocked yes)
			(layer "F.Fab")
			(hide yes)
			(effects
				(font
					(size 1.016 1.016)
					(thickness 0.1524)
				)
			)
		)
		(property "Device Type" "R402H16"
			(at 0.064008 -5.517896 90)
			(unlocked yes)
			(layer "F.Fab")
			(hide yes)
			(effects
				(font
					(size 1.016 1.016)
					(thickness 0.1524)
				)
			)
		)
		(duplicate_pad_numbers_are_jumpers no)
		(fp_line
			(start 0.508 -0.9398)
			(end -0.508 -0.9398)
			(stroke
				(width 0.1524)
				(type default)
			)
			(layer "F.SilkS")
		)
		(fp_line
			(start -0.508 -0.9398)
			(end -0.508 0.9398)
			(stroke
				(width 0.1524)
				(type default)
			)
			(layer "F.SilkS")
		)
		(fp_rect
			(start -0.508 0.9398)
			(end 0.508 -0.9398)
			(stroke
				(width 0)
				(type default)
			)
			(fill no)
			(layer "F.CrtYd")
		)
		(fp_rect
			(start -0.508 0.9398)
			(end 0.508 -0.9398)
			(stroke
				(width 0)
				(type default)
			)
			(fill no)
			(layer "F.Fab")
		)
		(pad "1" smd custom
			(at 0 -0.4445 90)
			(size 0.1397 0.1397)
			(layers "F.Cu" "F.Mask" "F.Paste")
			(net "P3V3_STBY_B")
			(options
				(clearance outline)
				(anchor circle)
			)
			(primitives
				(gr_poly
					(pts
						(arc
							(start -0.1778 -0.2794)
							(mid -0.249642 -0.249642)
							(end -0.2794 -0.1778)
						)
						(arc
							(start -0.2794 0.1778)
							(mid -0.249642 0.249642)
							(end -0.1778 0.2794)
						)
						(arc
							(start 0.1778 0.2794)
							(mid 0.249642 0.249642)
							(end 0.2794 0.1778)
						)
						(arc
							(start 0.2794 -0.1778)
							(mid 0.249642 -0.249642)
							(end 0.1778 -0.2794)
						)
					)
					(width 0)
					(fill yes)
				)
			)
		)
		(pad "2" smd custom
			(at 0 0.4445 90)
			(size 0.1397 0.1397)
			(layers "F.Cu" "F.Mask" "F.Paste")
			(net "SCC_B_PWR_LED")
			(options
				(clearance outline)
				(anchor circle)
			)
			(primitives
				(gr_poly
					(pts
						(arc
							(start -0.1778 -0.2794)
							(mid -0.249642 -0.249642)
							(end -0.2794 -0.1778)
						)
						(arc
							(start -0.2794 0.1778)
							(mid -0.249642 0.249642)
							(end -0.1778 0.2794)
						)
						(arc
							(start 0.1778 0.2794)
							(mid 0.249642 0.249642)
							(end 0.2794 0.1778)
						)
						(arc
							(start 0.2794 -0.1778)
							(mid 0.249642 -0.249642)
							(end 0.1778 -0.2794)
						)
					)
					(width 0)
					(fill yes)
				)
			)
		)
	)
	(footprint ""
		(layer "F.Cu")
		(at 318.2112 -295.0972 -90)
		(property "Reference" "R272"
			(at 0 0 270)
			(layer "F.SilkS")
			(hide yes)
			(effects
				(font
					(size 1.27 1.27)
				)
			)
		)
		(property "Value" "220R3F-1-GP"
			(at -0.0254 -2.5146 270)
			(unlocked yes)
			(layer "F.Fab")
			(hide yes)
			(effects
				(font
					(size 1.016 1.016)
					(thickness 0.1524)
				)
			)
		)
		(property "Device Type" "R603H22"
			(at -0.0254 -4.0386 270)
			(unlocked yes)
			(layer "F.Fab")
			(hide yes)
			(effects
				(font
					(size 1.016 1.016)
					(thickness 0.1524)
				)
			)
		)
		(duplicate_pad_numbers_are_jumpers no)
		(fp_line
			(start -0.4826 0)
			(end -0.2032 0)
			(stroke
				(width 0.2032)
				(type default)
			)
			(layer "F.SilkS")
		)
		(fp_line
			(start 0.2032 0)
			(end 0.4826 0)
			(stroke
				(width 0.2032)
				(type default)
			)
			(layer "F.SilkS")
		)
		(fp_rect
			(start -0.5842 1.3335)
			(end 0.5842 -1.3335)
			(stroke
				(width 0)
				(type default)
			)
			(fill no)
			(layer "F.CrtYd")
		)
		(fp_rect
			(start -0.5842 1.3335)
			(end 0.5842 -1.3335)
			(stroke
				(width 0)
				(type default)
			)
			(fill no)
			(layer "F.Fab")
		)
		(pad "1" smd custom
			(at 0 -0.762 270)
			(size 0.2159 0.2159)
			(layers "F.Cu" "F.Mask" "F.Paste")
			(net "HDD_PRSNT_6")
			(options
				(clearance outline)
				(anchor circle)
			)
			(primitives
				(gr_poly
					(pts
						(arc
							(start -0.3302 -0.4318)
							(mid -0.402042 -0.402042)
							(end -0.4318 -0.3302)
						)
						(arc
							(start -0.4318 0.3302)
							(mid -0.402042 0.402042)
							(end -0.3302 0.4318)
						)
						(arc
							(start 0.3302 0.4318)
							(mid 0.402042 0.402042)
							(end 0.4318 0.3302)
						)
						(arc
							(start 0.4318 -0.3302)
							(mid 0.402042 -0.402042)
							(end 0.3302 -0.4318)
						)
					)
					(width 0)
					(fill yes)
				)
			)
		)
		(pad "2" smd custom
			(at 0 0.762 270)
			(size 0.2159 0.2159)
			(layers "F.Cu" "F.Mask" "F.Paste")
			(net "DRIVE_A_6_INS")
			(options
				(clearance outline)
				(anchor circle)
			)
			(primitives
				(gr_poly
					(pts
						(arc
							(start -0.3302 -0.4318)
							(mid -0.402042 -0.402042)
							(end -0.4318 -0.3302)
						)
						(arc
							(start -0.4318 0.3302)
							(mid -0.402042 0.402042)
							(end -0.3302 0.4318)
						)
						(arc
							(start 0.3302 0.4318)
							(mid 0.402042 0.402042)
							(end 0.4318 0.3302)
						)
						(arc
							(start 0.4318 -0.3302)
							(mid 0.402042 -0.402042)
							(end 0.3302 -0.4318)
						)
					)
					(width 0)
					(fill yes)
				)
			)
		)
	)
	(footprint ""
		(layer "F.Cu")
		(at 242.5446 -242.6716 180)
		(property "Reference" "R82"
			(at 0 0 180)
			(layer "F.SilkS")
			(hide yes)
			(effects
				(font
					(size 1.27 1.27)
				)
			)
		)
		(property "Value" "0R2J-2-GP"
			(at 0.064008 -3.993896 180)
			(unlocked yes)
			(layer "F.Fab")
			(hide yes)
			(effects
				(font
					(size 1.016 1.016)
					(thickness 0.1524)
				)
			)
		)
		(property "Device Type" "R402H16"
			(at 0.064008 -5.517896 180)
			(unlocked yes)
			(layer "F.Fab")
			(hide yes)
			(effects
				(font
					(size 1.016 1.016)
					(thickness 0.1524)
				)
			)
		)
		(duplicate_pad_numbers_are_jumpers no)
		(fp_line
			(start 0.508 -0.9398)
			(end -0.508 -0.9398)
			(stroke
				(width 0.1524)
				(type default)
			)
			(layer "F.SilkS")
		)
		(fp_line
			(start -0.508 -0.9398)
			(end -0.508 0.9398)
			(stroke
				(width 0.1524)
				(type default)
			)
			(layer "F.SilkS")
		)
		(fp_rect
			(start -0.508 0.9398)
			(end 0.508 -0.9398)
			(stroke
				(width 0)
				(type default)
			)
			(fill no)
			(layer "F.CrtYd")
		)
		(fp_rect
			(start -0.508 0.9398)
			(end 0.508 -0.9398)
			(stroke
				(width 0)
				(type default)
			)
			(fill no)
			(layer "F.Fab")
		)
		(pad "1" smd custom
			(at 0 -0.4445 180)
			(size 0.1397 0.1397)
			(layers "F.Cu" "F.Mask" "F.Paste")
			(net "IO_EXP2_SCL")
			(options
				(clearance outline)
				(anchor circle)
			)
			(primitives
				(gr_poly
					(pts
						(arc
							(start -0.1778 -0.2794)
							(mid -0.249642 -0.249642)
							(end -0.2794 -0.1778)
						)
						(arc
							(start -0.2794 0.1778)
							(mid -0.249642 0.249642)
							(end -0.1778 0.2794)
						)
						(arc
							(start 0.1778 0.2794)
							(mid 0.249642 0.249642)
							(end 0.2794 0.1778)
						)
						(arc
							(start 0.2794 -0.1778)
							(mid 0.249642 -0.249642)
							(end 0.1778 -0.2794)
						)
					)
					(width 0)
					(fill yes)
				)
			)
		)
		(pad "2" smd custom
			(at 0 0.4445 180)
			(size 0.1397 0.1397)
			(layers "F.Cu" "F.Mask" "F.Paste")
			(net "I2C_DRIVE_A_PWR_SCL")
			(options
				(clearance outline)
				(anchor circle)
			)
			(primitives
				(gr_poly
					(pts
						(arc
							(start -0.1778 -0.2794)
							(mid -0.249642 -0.249642)
							(end -0.2794 -0.1778)
						)
						(arc
							(start -0.2794 0.1778)
							(mid -0.249642 0.249642)
							(end -0.1778 0.2794)
						)
						(arc
							(start 0.1778 0.2794)
							(mid 0.249642 0.249642)
							(end 0.2794 0.1778)
						)
						(arc
							(start 0.2794 -0.1778)
							(mid 0.249642 -0.249642)
							(end 0.1778 -0.2794)
						)
					)
					(width 0)
					(fill yes)
				)
			)
		)
	)
	(footprint ""
		(layer "F.Cu")
		(at 143.074898 -276.649942 180)
		(property "Reference" "D4"
			(at 0 0 180)
			(layer "F.SilkS")
			(hide yes)
			(effects
				(font
					(size 1.27 1.27)
				)
			)
		)
		(property "Value" "RB551V30-GP"
			(at 0 -6.7818 180)
			(unlocked yes)
			(layer "F.Fab")
			(hide yes)
			(effects
				(font
					(size 1.016 1.016)
					(thickness 0.1524)
				)
			)
		)
		(property "Device Type" "SOD323AKH38"
			(at 0 -8.6868 180)
			(unlocked yes)
			(layer "F.Fab")
			(hide yes)
			(effects
				(font
					(size 1.016 1.016)
					(thickness 0.1524)
				)
			)
		)
		(duplicate_pad_numbers_are_jumpers no)
		(fp_line
			(start 0.889 2.159)
			(end -0.889 2.159)
			(stroke
				(width 0.1524)
				(type default)
			)
			(layer "F.SilkS")
		)
		(fp_line
			(start 0.889 -1.9304)
			(end 0.889 2.159)
			(stroke
				(width 0.1524)
				(type default)
			)
			(layer "F.SilkS")
		)
		(fp_line
			(start 0.762 2.0574)
			(end -0.762 2.0574)
			(stroke
				(width 0.508)
				(type default)
			)
			(layer "F.SilkS")
		)
		(fp_line
			(start -0.889 2.159)
			(end -0.889 -1.9304)
			(stroke
				(width 0.1524)
				(type default)
			)
			(layer "F.SilkS")
		)
		(fp_line
			(start -0.889 -1.9304)
			(end 0.889 -1.9304)
			(stroke
				(width 0.1524)
				(type default)
			)
			(layer "F.SilkS")
		)
		(fp_rect
			(start -1.016 2.3114)
			(end 1.016 -2.0066)
			(stroke
				(width 0)
				(type default)
			)
			(fill no)
			(layer "F.CrtYd")
		)
		(fp_poly
			(pts
				(xy -1.016 -2.0066) (xy 1.016 -2.0066) (xy 1.016 2.3114) (xy -1.016 2.3114)
			)
			(stroke
				(width 0)
				(type default)
			)
			(fill no)
			(layer "F.Fab")
		)
		(pad "A" smd rect
			(at 0 -1.143 180)
			(size 0.5588 1.016)
			(layers "F.Cu" "F.Mask" "F.Paste")
			(net "SW_HDD_R4")
		)
		(pad "K" smd rect
			(at 0 1.143 180)
			(size 0.5588 1.016)
			(layers "F.Cu" "F.Mask" "F.Paste")
			(net "SW_HDD_N4")
		)
	)
	(footprint ""
		(layer "F.Cu")
		(at 222.746824 -347.3577 180)
		(property "Reference" "C5"
			(at 0 0 180)
			(layer "F.SilkS")
			(hide yes)
			(effects
				(font
					(size 1.27 1.27)
				)
			)
		)
		(property "Value" "SCD1U16V2KX-3GP"
			(at 1.1811 -2.7051 180)
			(unlocked yes)
			(layer "F.Fab")
			(hide yes)
			(effects
				(font
					(size 1.016 1.016)
					(thickness 0.1524)
				)
			)
		)
		(property "Device Type" "C402H22"
			(at 1.1811 -4.2291 180)
			(unlocked yes)
			(layer "F.Fab")
			(hide yes)
			(effects
				(font
					(size 1.016 1.016)
					(thickness 0.1524)
				)
			)
		)
		(duplicate_pad_numbers_are_jumpers no)
		(fp_rect
			(start -0.4318 0.9525)
			(end 0.4318 -0.9525)
			(stroke
				(width 0)
				(type default)
			)
			(fill no)
			(layer "F.CrtYd")
		)
		(fp_rect
			(start -0.4318 0.9525)
			(end 0.4318 -0.9525)
			(stroke
				(width 0)
				(type default)
			)
			(fill no)
			(layer "F.Fab")
		)
		(pad "1" smd custom
			(at 0 -0.4445 180)
			(size 0.1524 0.1524)
			(layers "F.Cu" "F.Mask" "F.Paste")
			(net "P3V3_STBY_A")
			(options
				(clearance outline)
				(anchor circle)
			)
			(primitives
				(gr_poly
					(pts
						(arc
							(start 0.3048 -0.2032)
							(mid 0.275042 -0.275042)
							(end 0.2032 -0.3048)
						)
						(arc
							(start -0.2032 -0.3048)
							(mid -0.275042 -0.275042)
							(end -0.3048 -0.2032)
						)
						(arc
							(start -0.3048 0.2032)
							(mid -0.275042 0.275042)
							(end -0.2032 0.3048)
						)
						(arc
							(start 0.2032 0.3048)
							(mid 0.275042 0.275042)
							(end 0.3048 0.2032)
						)
					)
					(width 0)
					(fill yes)
				)
			)
		)
		(pad "2" smd custom
			(at 0 0.4445 180)
			(size 0.1524 0.1524)
			(layers "F.Cu" "F.Mask" "F.Paste")
			(net "GND")
			(options
				(clearance outline)
				(anchor circle)
			)
			(primitives
				(gr_poly
					(pts
						(arc
							(start 0.3048 -0.2032)
							(mid 0.275042 -0.275042)
							(end 0.2032 -0.3048)
						)
						(arc
							(start -0.2032 -0.3048)
							(mid -0.275042 -0.275042)
							(end -0.3048 -0.2032)
						)
						(arc
							(start -0.3048 0.2032)
							(mid -0.275042 0.275042)
							(end -0.2032 0.3048)
						)
						(arc
							(start 0.2032 0.3048)
							(mid 0.275042 0.275042)
							(end 0.3048 0.2032)
						)
					)
					(width 0)
					(fill yes)
				)
			)
		)
	)
)
